(kicad_pcb
	(version 20241229)
	(generator "pcbnew")
	(generator_version "9.0")
	(general
		(thickness 1.599998)
		(legacy_teardrops no)
	)
	(paper "A4")
	(title_block
		(date "2023-02-12")
		(rev "1.1.5")
		(comment 9 "footprints 152-157 of 473")
	)
	(layers
		(0 "F.Cu" signal)
		(4 "In1.Cu" power "In1.GND")
		(6 "In2.Cu" signal)
		(8 "In3.Cu" power "In3.GND")
		(10 "In4.Cu" power "In4.VCC")
		(12 "In5.Cu" signal)
		(14 "In6.Cu" power "In6.VCC")
		(2 "B.Cu" signal)
		(9 "F.Adhes" user "F.Adhesive")
		(11 "B.Adhes" user "B.Adhesive")
		(13 "F.Paste" user)
		(15 "B.Paste" user)
		(5 "F.SilkS" user "F.Silkscreen")
		(7 "B.SilkS" user "B.Silkscreen")
		(1 "F.Mask" user)
		(3 "B.Mask" user)
		(17 "Dwgs.User" user "User.Drawings")
		(19 "Cmts.User" user "User.Comments")
		(21 "Eco1.User" user "User.Eco1")
		(23 "Eco2.User" user "User.Eco2")
		(25 "Edge.Cuts" user)
		(27 "Margin" user)
		(31 "F.CrtYd" user "F.Courtyard")
		(29 "B.CrtYd" user "B.Courtyard")
		(35 "F.Fab" user)
		(33 "B.Fab" user)
	)
	(footprint "antmicro-footprints:SW_B3U-1000P_SMD"
		(layer "F.Cu")
		(at 200.936328 67.947157 90)
		(property "Reference" "USR_BTN3"
			(at 0 -1.8 90)
			(layer "F.SilkS")
			(effects
				(font
					(size 0.7 0.7)
					(thickness 0.15)
				)
				(justify left bottom)
			)
		)
		(property "Value" "SW_B3U-1000P"
			(at 0 2.5 90)
			(layer "F.Fab")
			(effects
				(font
					(size 0.7 0.7)
					(thickness 0.15)
				)
				(justify left bottom)
			)
		)
		(property "Description" "Tactile Switch, B3U, Top Actuated, Surface Mount, Round Button, 153 gf, 50mA at 12VDC"
			(at 0 0 90)
			(layer "F.Fab")
			(hide yes)
			(effects
				(font
					(size 1.27 1.27)
					(thickness 0.15)
				)
			)
		)
		(property "Author" "Antmicro"
			(at 268.883485 -132.989171 0)
			(layer "F.Fab")
			(hide yes)
			(effects
				(font
					(size 1 1)
					(thickness 0.15)
				)
			)
		)
		(property "License" "Apache-2.0"
			(at 268.883485 -132.989171 0)
			(layer "F.Fab")
			(hide yes)
			(effects
				(font
					(size 1 1)
					(thickness 0.15)
				)
			)
		)
		(property "MPN" "B3U-1000P"
			(at 268.883485 -132.989171 0)
			(layer "F.Fab")
			(hide yes)
			(effects
				(font
					(size 1 1)
					(thickness 0.15)
				)
			)
		)
		(property "Manufacturer" "Omron"
			(at 268.883485 -132.989171 0)
			(layer "F.Fab")
			(hide yes)
			(effects
				(font
					(size 1 1)
					(thickness 0.15)
				)
			)
		)
		(sheetname "Interfaces")
		(sheetfile "interfaces.kicad_sch")
		(attr smd)
		(fp_line
			(start 1.6 -1.4)
			(end 1.1 -1.4)
			(stroke
				(width 0.15)
				(type solid)
			)
			(layer "F.SilkS")
		)
		(fp_line
			(start 1.6 -1.4)
			(end 1.6 -0.95)
			(stroke
				(width 0.15)
				(type solid)
			)
			(layer "F.SilkS")
		)
		(fp_line
			(start -1.6 -1.4)
			(end -1.1 -1.4)
			(stroke
				(width 0.15)
				(type solid)
			)
			(layer "F.SilkS")
		)
		(fp_line
			(start -1.6 -1.4)
			(end -1.601 -0.95)
			(stroke
				(width 0.15)
				(type solid)
			)
			(layer "F.SilkS")
		)
		(fp_line
			(start -1.601 -0.95)
			(end -2 -0.95)
			(stroke
				(width 0.15)
				(type solid)
			)
			(layer "F.SilkS")
		)
		(fp_line
			(start 1.6 1.4)
			(end 1.6 0.95)
			(stroke
				(width 0.15)
				(type solid)
			)
			(layer "F.SilkS")
		)
		(fp_line
			(start 1.6 1.4)
			(end 1.1 1.4)
			(stroke
				(width 0.15)
				(type solid)
			)
			(layer "F.SilkS")
		)
		(fp_line
			(start -1.6 1.4)
			(end -1.6 0.95)
			(stroke
				(width 0.15)
				(type solid)
			)
			(layer "F.SilkS")
		)
		(fp_line
			(start -1.6 1.4)
			(end -1.1 1.4)
			(stroke
				(width 0.15)
				(type solid)
			)
			(layer "F.SilkS")
		)
		(fp_rect
			(start -2.249 -1.55)
			(end 2.25 1.549)
			(stroke
				(width 0.05)
				(type solid)
			)
			(fill no)
			(layer "F.CrtYd")
		)
		(fp_rect
			(start -1.5 -1.29)
			(end 1.499 1.289)
			(stroke
				(width 0.15)
				(type solid)
			)
			(fill no)
			(layer "F.Fab")
		)
		(pad "1" smd rect
			(at -1.7 0 90)
			(size 0.8 1.7)
			(layers "F.Cu" "F.Mask" "F.Paste")
			(net 392 "USR_BTN3")
			(pinfunction "1")
			(pintype "passive")
		)
		(pad "2" smd rect
			(at 1.699 0 90)
			(size 0.8 1.7)
			(layers "F.Cu" "F.Mask" "F.Paste")
			(net 5 "GND")
			(pinfunction "2")
			(pintype "passive")
		)
	)
	(footprint "antmicro-footprints:R_0402_1005Metric"
		(layer "F.Cu")
		(at 192.736328 71.697157 90)
		(descr "Resistor SMD 0402")
		(tags "resistor SMD 0402")
		(property "Reference" "R9"
			(at -1.102843 1.263672 90)
			(layer "F.SilkS")
			(effects
				(font
					(size 0.7 0.7)
					(thickness 0.15)
				)
				(justify left bottom)
			)
		)
		(property "Value" "R_4k7_0402"
			(at 0 1.4 90)
			(layer "F.Fab")
			(effects
				(font
					(size 0.7 0.7)
					(thickness 0.15)
				)
				(justify left bottom)
			)
		)
		(property "Description" "4k7 resistor in 0402 package with 1% tolerance"
			(at 0 0 90)
			(layer "F.Fab")
			(hide yes)
			(effects
				(font
					(size 1.27 1.27)
					(thickness 0.15)
				)
			)
		)
		(property "Author" "Antmicro"
			(at 264.433485 -121.039171 0)
			(layer "F.Fab")
			(hide yes)
			(effects
				(font
					(size 1 1)
					(thickness 0.15)
				)
			)
		)
		(property "License" "Apache-2.0"
			(at 264.433485 -121.039171 0)
			(layer "F.Fab")
			(hide yes)
			(effects
				(font
					(size 1 1)
					(thickness 0.15)
				)
			)
		)
		(property "MPN" "CR0402-FX-4701GLF"
			(at 264.433485 -121.039171 0)
			(layer "F.Fab")
			(hide yes)
			(effects
				(font
					(size 1 1)
					(thickness 0.15)
				)
			)
		)
		(property "Manufacturer" "Bourns"
			(at 264.433485 -121.039171 0)
			(layer "F.Fab")
			(hide yes)
			(effects
				(font
					(size 1 1)
					(thickness 0.15)
				)
			)
		)
		(property "Tolerance" "1%"
			(at 264.433485 -121.039171 0)
			(layer "F.Fab")
			(hide yes)
			(effects
				(font
					(size 1 1)
					(thickness 0.15)
				)
			)
		)
		(property "Val" "4k7"
			(at 264.433485 -121.039171 0)
			(layer "F.Fab")
			(hide yes)
			(effects
				(font
					(size 1 1)
					(thickness 0.15)
				)
			)
		)
		(sheetname "Interfaces")
		(sheetfile "interfaces.kicad_sch")
		(attr smd)
		(fp_rect
			(start -0.93 -0.47)
			(end 0.93 0.47)
			(stroke
				(width 0.05)
				(type solid)
			)
			(fill no)
			(layer "F.CrtYd")
		)
		(fp_rect
			(start -0.5 -0.25)
			(end 0.5 0.25)
			(stroke
				(width 0.15)
				(type solid)
			)
			(fill no)
			(layer "F.Fab")
		)
		(pad "1" smd roundrect
			(at -0.485 0 90)
			(size 0.59 0.64)
			(layers "F.Cu" "F.Mask" "F.Paste")
			(roundrect_rratio 0.25)
			(net 459 "3V3_SYS")
			(pintype "passive")
		)
		(pad "2" smd roundrect
			(at 0.485 0 90)
			(size 0.59 0.64)
			(layers "F.Cu" "F.Mask" "F.Paste")
			(roundrect_rratio 0.25)
			(net 390 "USR_BTN1")
			(pintype "passive")
		)
	)
	(footprint "antmicro-footprints:R_0402_1005Metric"
		(layer "F.Cu")
		(at 196.736328 71.697157 90)
		(descr "Resistor SMD 0402")
		(tags "resistor SMD 0402")
		(property "Reference" "R10"
			(at -1.102843 1.263672 90)
			(layer "F.SilkS")
			(effects
				(font
					(size 0.7 0.7)
					(thickness 0.15)
				)
				(justify left bottom)
			)
		)
		(property "Value" "R_4k7_0402"
			(at 0 1.4 90)
			(layer "F.Fab")
			(effects
				(font
					(size 0.7 0.7)
					(thickness 0.15)
				)
				(justify left bottom)
			)
		)
		(property "Description" "4k7 resistor in 0402 package with 1% tolerance"
			(at 0 0 90)
			(layer "F.Fab")
			(hide yes)
			(effects
				(font
					(size 1.27 1.27)
					(thickness 0.15)
				)
			)
		)
		(property "Author" "Antmicro"
			(at 268.433485 -125.039171 0)
			(layer "F.Fab")
			(hide yes)
			(effects
				(font
					(size 1 1)
					(thickness 0.15)
				)
			)
		)
		(property "License" "Apache-2.0"
			(at 268.433485 -125.039171 0)
			(layer "F.Fab")
			(hide yes)
			(effects
				(font
					(size 1 1)
					(thickness 0.15)
				)
			)
		)
		(property "MPN" "CR0402-FX-4701GLF"
			(at 268.433485 -125.039171 0)
			(layer "F.Fab")
			(hide yes)
			(effects
				(font
					(size 1 1)
					(thickness 0.15)
				)
			)
		)
		(property "Manufacturer" "Bourns"
			(at 268.433485 -125.039171 0)
			(layer "F.Fab")
			(hide yes)
			(effects
				(font
					(size 1 1)
					(thickness 0.15)
				)
			)
		)
		(property "Tolerance" "1%"
			(at 268.433485 -125.039171 0)
			(layer "F.Fab")
			(hide yes)
			(effects
				(font
					(size 1 1)
					(thickness 0.15)
				)
			)
		)
		(property "Val" "4k7"
			(at 268.433485 -125.039171 0)
			(layer "F.Fab")
			(hide yes)
			(effects
				(font
					(size 1 1)
					(thickness 0.15)
				)
			)
		)
		(sheetname "Interfaces")
		(sheetfile "interfaces.kicad_sch")
		(attr smd)
		(fp_rect
			(start -0.93 -0.47)
			(end 0.93 0.47)
			(stroke
				(width 0.05)
				(type solid)
			)
			(fill no)
			(layer "F.CrtYd")
		)
		(fp_rect
			(start -0.5 -0.25)
			(end 0.5 0.25)
			(stroke
				(width 0.15)
				(type solid)
			)
			(fill no)
			(layer "F.Fab")
		)
		(pad "1" smd roundrect
			(at -0.485 0 90)
			(size 0.59 0.64)
			(layers "F.Cu" "F.Mask" "F.Paste")
			(roundrect_rratio 0.25)
			(net 459 "3V3_SYS")
			(pintype "passive")
		)
		(pad "2" smd roundrect
			(at 0.485 0 90)
			(size 0.59 0.64)
			(layers "F.Cu" "F.Mask" "F.Paste")
			(roundrect_rratio 0.25)
			(net 391 "USR_BTN2")
			(pintype "passive")
		)
	)
	(footprint "antmicro-footprints:R_0402_1005Metric"
		(layer "F.Cu")
		(at 200.736328 71.697157 90)
		(descr "Resistor SMD 0402")
		(tags "resistor SMD 0402")
		(property "Reference" "R11"
			(at -1.102843 1.263672 90)
			(layer "F.SilkS")
			(effects
				(font
					(size 0.7 0.7)
					(thickness 0.15)
				)
				(justify left bottom)
			)
		)
		(property "Value" "R_4k7_0402"
			(at 0 1.4 90)
			(layer "F.Fab")
			(effects
				(font
					(size 0.7 0.7)
					(thickness 0.15)
				)
				(justify left bottom)
			)
		)
		(property "Description" "4k7 resistor in 0402 package with 1% tolerance"
			(at 0 0 90)
			(layer "F.Fab")
			(hide yes)
			(effects
				(font
					(size 1.27 1.27)
					(thickness 0.15)
				)
			)
		)
		(property "Author" "Antmicro"
			(at 272.433485 -129.039171 0)
			(layer "F.Fab")
			(hide yes)
			(effects
				(font
					(size 1 1)
					(thickness 0.15)
				)
			)
		)
		(property "License" "Apache-2.0"
			(at 272.433485 -129.039171 0)
			(layer "F.Fab")
			(hide yes)
			(effects
				(font
					(size 1 1)
					(thickness 0.15)
				)
			)
		)
		(property "MPN" "CR0402-FX-4701GLF"
			(at 272.433485 -129.039171 0)
			(layer "F.Fab")
			(hide yes)
			(effects
				(font
					(size 1 1)
					(thickness 0.15)
				)
			)
		)
		(property "Manufacturer" "Bourns"
			(at 272.433485 -129.039171 0)
			(layer "F.Fab")
			(hide yes)
			(effects
				(font
					(size 1 1)
					(thickness 0.15)
				)
			)
		)
		(property "Tolerance" "1%"
			(at 272.433485 -129.039171 0)
			(layer "F.Fab")
			(hide yes)
			(effects
				(font
					(size 1 1)
					(thickness 0.15)
				)
			)
		)
		(property "Val" "4k7"
			(at 272.433485 -129.039171 0)
			(layer "F.Fab")
			(hide yes)
			(effects
				(font
					(size 1 1)
					(thickness 0.15)
				)
			)
		)
		(sheetname "Interfaces")
		(sheetfile "interfaces.kicad_sch")
		(attr smd)
		(fp_rect
			(start -0.93 -0.47)
			(end 0.93 0.47)
			(stroke
				(width 0.05)
				(type solid)
			)
			(fill no)
			(layer "F.CrtYd")
		)
		(fp_rect
			(start -0.5 -0.25)
			(end 0.5 0.25)
			(stroke
				(width 0.15)
				(type solid)
			)
			(fill no)
			(layer "F.Fab")
		)
		(pad "1" smd roundrect
			(at -0.485 0 90)
			(size 0.59 0.64)
			(layers "F.Cu" "F.Mask" "F.Paste")
			(roundrect_rratio 0.25)
			(net 459 "3V3_SYS")
			(pintype "passive")
		)
		(pad "2" smd roundrect
			(at 0.485 0 90)
			(size 0.59 0.64)
			(layers "F.Cu" "F.Mask" "F.Paste")
			(roundrect_rratio 0.25)
			(net 392 "USR_BTN3")
			(pintype "passive")
		)
	)
	(footprint "antmicro-footprints:R_0402_1005Metric"
		(layer "F.Cu")
		(at 204.736328 71.697157 90)
		(descr "Resistor SMD 0402")
		(tags "resistor SMD 0402")
		(property "Reference" "R12"
			(at -1.102843 1.263672 90)
			(layer "F.SilkS")
			(effects
				(font
					(size 0.7 0.7)
					(thickness 0.15)
				)
				(justify left bottom)
			)
		)
		(property "Value" "R_4k7_0402"
			(at 0 1.4 90)
			(layer "F.Fab")
			(effects
				(font
					(size 0.7 0.7)
					(thickness 0.15)
				)
				(justify left bottom)
			)
		)
		(property "Description" "4k7 resistor in 0402 package with 1% tolerance"
			(at 0 0 90)
			(layer "F.Fab")
			(hide yes)
			(effects
				(font
					(size 1.27 1.27)
					(thickness 0.15)
				)
			)
		)
		(property "Author" "Antmicro"
			(at 276.433485 -133.039171 0)
			(layer "F.Fab")
			(hide yes)
			(effects
				(font
					(size 1 1)
					(thickness 0.15)
				)
			)
		)
		(property "License" "Apache-2.0"
			(at 276.433485 -133.039171 0)
			(layer "F.Fab")
			(hide yes)
			(effects
				(font
					(size 1 1)
					(thickness 0.15)
				)
			)
		)
		(property "MPN" "CR0402-FX-4701GLF"
			(at 276.433485 -133.039171 0)
			(layer "F.Fab")
			(hide yes)
			(effects
				(font
					(size 1 1)
					(thickness 0.15)
				)
			)
		)
		(property "Manufacturer" "Bourns"
			(at 276.433485 -133.039171 0)
			(layer "F.Fab")
			(hide yes)
			(effects
				(font
					(size 1 1)
					(thickness 0.15)
				)
			)
		)
		(property "Tolerance" "1%"
			(at 276.433485 -133.039171 0)
			(layer "F.Fab")
			(hide yes)
			(effects
				(font
					(size 1 1)
					(thickness 0.15)
				)
			)
		)
		(property "Val" "4k7"
			(at 276.433485 -133.039171 0)
			(layer "F.Fab")
			(hide yes)
			(effects
				(font
					(size 1 1)
					(thickness 0.15)
				)
			)
		)
		(sheetname "Interfaces")
		(sheetfile "interfaces.kicad_sch")
		(attr smd)
		(fp_rect
			(start -0.93 -0.47)
			(end 0.93 0.47)
			(stroke
				(width 0.05)
				(type solid)
			)
			(fill no)
			(layer "F.CrtYd")
		)
		(fp_rect
			(start -0.5 -0.25)
			(end 0.5 0.25)
			(stroke
				(width 0.15)
				(type solid)
			)
			(fill no)
			(layer "F.Fab")
		)
		(pad "1" smd roundrect
			(at -0.485 0 90)
			(size 0.59 0.64)
			(layers "F.Cu" "F.Mask" "F.Paste")
			(roundrect_rratio 0.25)
			(net 459 "3V3_SYS")
			(pintype "passive")
		)
		(pad "2" smd roundrect
			(at 0.485 0 90)
			(size 0.59 0.64)
			(layers "F.Cu" "F.Mask" "F.Paste")
			(roundrect_rratio 0.25)
			(net 436 "USR_BTN4")
			(pintype "passive")
		)
	)
	(footprint "antmicro-footprints:SW_B3U-1000P_SMD"
		(layer "F.Cu")
		(at 205.336328 67.997157 90)
		(property "Reference" "USR_BTN4"
			(at 0 -1.8 90)
			(layer "F.SilkS")
			(effects
				(font
					(size 0.7 0.7)
					(thickness 0.15)
				)
				(justify left bottom)
			)
		)
		(property "Value" "SW_B3U-1000P"
			(at 0 2.5 90)
			(layer "F.Fab")
			(effects
				(font
					(size 0.7 0.7)
					(thickness 0.15)
				)
				(justify left bottom)
			)
		)
		(property "Description" "Tactile Switch, B3U, Top Actuated, Surface Mount, Round Button, 153 gf, 50mA at 12VDC"
			(at 0 0 90)
			(layer "F.Fab")
			(hide yes)
			(effects
				(font
					(size 1.27 1.27)
					(thickness 0.15)
				)
			)
		)
		(property "Author" "Antmicro"
			(at 273.333485 -137.339171 0)
			(layer "F.Fab")
			(hide yes)
			(effects
				(font
					(size 1 1)
					(thickness 0.15)
				)
			)
		)
		(property "License" "Apache-2.0"
			(at 273.333485 -137.339171 0)
			(layer "F.Fab")
			(hide yes)
			(effects
				(font
					(size 1 1)
					(thickness 0.15)
				)
			)
		)
		(property "MPN" "B3U-1000P"
			(at 273.333485 -137.339171 0)
			(layer "F.Fab")
			(hide yes)
			(effects
				(font
					(size 1 1)
					(thickness 0.15)
				)
			)
		)
		(property "Manufacturer" "Omron"
			(at 273.333485 -137.339171 0)
			(layer "F.Fab")
			(hide yes)
			(effects
				(font
					(size 1 1)
					(thickness 0.15)
				)
			)
		)
		(sheetname "Interfaces")
		(sheetfile "interfaces.kicad_sch")
		(attr smd)
		(fp_line
			(start 1.6 -1.4)
			(end 1.1 -1.4)
			(stroke
				(width 0.15)
				(type solid)
			)
			(layer "F.SilkS")
		)
		(fp_line
			(start 1.6 -1.4)
			(end 1.6 -0.95)
			(stroke
				(width 0.15)
				(type solid)
			)
			(layer "F.SilkS")
		)
		(fp_line
			(start -1.6 -1.4)
			(end -1.1 -1.4)
			(stroke
				(width 0.15)
				(type solid)
			)
			(layer "F.SilkS")
		)
		(fp_line
			(start -1.6 -1.4)
			(end -1.601 -0.95)
			(stroke
				(width 0.15)
				(type solid)
			)
			(layer "F.SilkS")
		)
		(fp_line
			(start -1.601 -0.95)
			(end -2 -0.95)
			(stroke
				(width 0.15)
				(type solid)
			)
			(layer "F.SilkS")
		)
		(fp_line
			(start 1.6 1.4)
			(end 1.6 0.95)
			(stroke
				(width 0.15)
				(type solid)
			)
			(layer "F.SilkS")
		)
		(fp_line
			(start 1.6 1.4)
			(end 1.1 1.4)
			(stroke
				(width 0.15)
				(type solid)
			)
			(layer "F.SilkS")
		)
		(fp_line
			(start -1.6 1.4)
			(end -1.6 0.95)
			(stroke
				(width 0.15)
				(type solid)
			)
			(layer "F.SilkS")
		)
		(fp_line
			(start -1.6 1.4)
			(end -1.1 1.4)
			(stroke
				(width 0.15)
				(type solid)
			)
			(layer "F.SilkS")
		)
		(fp_rect
			(start -2.249 -1.55)
			(end 2.25 1.549)
			(stroke
				(width 0.05)
				(type solid)
			)
			(fill no)
			(layer "F.CrtYd")
		)
		(fp_rect
			(start -1.5 -1.29)
			(end 1.499 1.289)
			(stroke
				(width 0.15)
				(type solid)
			)
			(fill no)
			(layer "F.Fab")
		)
		(pad "1" smd rect
			(at -1.7 0 90)
			(size 0.8 1.7)
			(layers "F.Cu" "F.Mask" "F.Paste")
			(net 436 "USR_BTN4")
			(pinfunction "1")
			(pintype "passive")
		)
		(pad "2" smd rect
			(at 1.699 0 90)
			(size 0.8 1.7)
			(layers "F.Cu" "F.Mask" "F.Paste")
			(net 5 "GND")
			(pinfunction "2")
			(pintype "passive")
		)
	)
)
